# S9S_MB_2U (Grand Teton) — schematic netlist excerpt (pin names and nets, part order shuffled) for the footprints in the layout excerpt that follows; sources: Cadence DE-HDL packaged netlist, KiCad conversion of 03242023_DA0F0TMBIJ0_F0T_Motherboard_J_brd_V01_OCP.brd

PR4683  Q_RES  0 5% CHIP  pkg 0402LF  page 282 : A = PVNN_MAIN_CPU0_FB_RC ; B = PVNN_MAIN_CPU0
R271  Q_RES  10K 1% CHIP  pkg 0402LF  page 119 : A = P3V3_AUX ; B = FM_CPU1_PKGID1

(kicad_pcb
	(version 20260206)
	(generator "pcbnew")
	(generator_version "10.0")
	(general
		(thickness 1.6)
		(legacy_teardrops no)
	)
	(paper "A4")
	(title_block
		(title "03242023_DA0F0TMBIJ0_F0T_Motherboard_J_brd_V01_OCP.brd")
		(comment 1 "Grand Teton / footprints 3747-3748 of 6105")
	)
	(layers
		(0 "F.Cu" signal "TOP")
		(4 "In1.Cu" signal "GND")
		(6 "In2.Cu" signal "IN1")
		(8 "In3.Cu" signal "GND1")
		(10 "In4.Cu" signal "IN2")
		(12 "In5.Cu" signal "GND2")
		(14 "In6.Cu" signal "IN3")
		(16 "In7.Cu" signal "GND3")
		(18 "In8.Cu" signal "VCC")
		(20 "In9.Cu" signal "VCC1")
		(22 "In10.Cu" signal "GND4")
		(24 "In11.Cu" signal "IN4")
		(26 "In12.Cu" signal "GND5")
		(28 "In13.Cu" signal "IN5")
		(30 "In14.Cu" signal "GND6")
		(32 "In15.Cu" signal "IN6")
		(34 "In16.Cu" signal "GND7")
		(2 "B.Cu" signal "BOTTOM")
		(9 "F.Adhes" user "F.Adhesive")
		(11 "B.Adhes" user "B.Adhesive")
		(13 "F.Paste" user "Package Geometry/Pastemask Top")
		(15 "B.Paste" user "Package Geometry/Pastemask Bottom")
		(5 "F.SilkS" user "Ref Des/Silkscreen Top")
		(7 "B.SilkS" user "Ref Des/Silkscreen Bottom")
		(1 "F.Mask" user "Board Geometry/Soldermask Top")
		(3 "B.Mask" user "Board Geometry/Soldermask Bottom")
		(17 "Dwgs.User" user "User.Drawings")
		(19 "Cmts.User" user "User.Comments")
		(21 "Eco1.User" user "User.Eco1")
		(23 "Eco2.User" user "User.Eco2")
		(25 "Edge.Cuts" user "Board Geometry/Outline")
		(27 "Margin" user)
		(31 "F.CrtYd" user "Package Geometry/Place Bound Top")
		(29 "B.CrtYd" user "Package Geometry/Place Bound Bottom")
		(35 "F.Fab" user "Ref Des/Assembly Top")
		(33 "B.Fab" user "Ref Des/Assembly Bottom")
	)
	(footprint ""
		(layer "F.Cu")
		(at 180.64988 -126.964948 -90)
		(property "Reference" "R271"
			(at 0 0 270)
			(layer "F.SilkS")
			(hide yes)
			(effects
				(font
					(size 1.27 1.27)
				)
			)
		)
		(property "Value" ""
			(at 0 0 270)
			(layer "F.Fab")
			(effects
				(font
					(size 1.27 1.27)
				)
			)
		)
		(duplicate_pad_numbers_are_jumpers no)
		(fp_line
			(start -0.7874 0.4064)
			(end -0.7874 -0.4064)
			(stroke
				(width 0.1524)
				(type default)
			)
			(layer "F.SilkS")
		)
		(fp_line
			(start 0.7874 0.4064)
			(end -0.7874 0.4064)
			(stroke
				(width 0.1524)
				(type default)
			)
			(layer "F.SilkS")
		)
		(fp_line
			(start -0.7874 -0.4064)
			(end 0.7874 -0.4064)
			(stroke
				(width 0.1524)
				(type default)
			)
			(layer "F.SilkS")
		)
		(fp_line
			(start 0.7874 -0.4064)
			(end 0.7874 0.4064)
			(stroke
				(width 0.1524)
				(type default)
			)
			(layer "F.SilkS")
		)
		(fp_line
			(start -0.67945 0.3048)
			(end -0.67945 -0.305054)
			(stroke
				(width 0.1)
				(type default)
			)
			(layer "F.Fab")
		)
		(fp_line
			(start -0.12065 0.3048)
			(end -0.67945 0.3048)
			(stroke
				(width 0.1)
				(type default)
			)
			(layer "F.Fab")
		)
		(fp_line
			(start 0.120396 0.3048)
			(end 0.120396 0.2794)
			(stroke
				(width 0.1)
				(type default)
			)
			(layer "F.Fab")
		)
		(fp_line
			(start 0.67945 0.3048)
			(end 0.120396 0.3048)
			(stroke
				(width 0.1)
				(type default)
			)
			(layer "F.Fab")
		)
		(fp_line
			(start -0.12065 0.2794)
			(end -0.12065 0.3048)
			(stroke
				(width 0.1)
				(type default)
			)
			(layer "F.Fab")
		)
		(fp_line
			(start 0.120396 0.2794)
			(end -0.12065 0.2794)
			(stroke
				(width 0.1)
				(type default)
			)
			(layer "F.Fab")
		)
		(fp_line
			(start -0.12065 -0.2794)
			(end 0.12065 -0.2794)
			(stroke
				(width 0.1)
				(type default)
			)
			(layer "F.Fab")
		)
		(fp_line
			(start 0.12065 -0.2794)
			(end 0.12065 -0.3048)
			(stroke
				(width 0.1)
				(type default)
			)
			(layer "F.Fab")
		)
		(fp_line
			(start 0.12065 -0.3048)
			(end 0.67945 -0.3048)
			(stroke
				(width 0.1)
				(type default)
			)
			(layer "F.Fab")
		)
		(fp_line
			(start 0.67945 -0.3048)
			(end 0.67945 0.3048)
			(stroke
				(width 0.1)
				(type default)
			)
			(layer "F.Fab")
		)
		(fp_line
			(start -0.67945 -0.305054)
			(end -0.12065 -0.305054)
			(stroke
				(width 0.1)
				(type default)
			)
			(layer "F.Fab")
		)
		(fp_line
			(start -0.12065 -0.305054)
			(end -0.12065 -0.2794)
			(stroke
				(width 0.1)
				(type default)
			)
			(layer "F.Fab")
		)
		(pad "1" smd circle
			(at -0.40005 0 270)
			(size 0 0)
			(layers "F.Cu" "F.Mask" "F.Paste")
			(net "P3V3_AUX")
		)
		(pad "2" smd circle
			(at 0.40005 0 270)
			(size 0 0)
			(layers "F.Cu" "F.Mask" "F.Paste")
			(net "FM_CPU1_PKGID1")
		)
	)
	(footprint ""
		(layer "F.Cu")
		(at 437.93537 -174.805594)
		(property "Reference" "PR4683"
			(at 0 0 0)
			(layer "F.SilkS")
			(hide yes)
			(effects
				(font
					(size 1.27 1.27)
				)
			)
		)
		(property "Value" ""
			(at 0 0 0)
			(layer "F.Fab")
			(effects
				(font
					(size 1.27 1.27)
				)
			)
		)
		(duplicate_pad_numbers_are_jumpers no)
		(fp_line
			(start -0.7874 -0.4064)
			(end 0.7874 -0.4064)
			(stroke
				(width 0.1524)
				(type default)
			)
			(layer "F.SilkS")
		)
		(fp_line
			(start -0.7874 0.4064)
			(end -0.7874 -0.4064)
			(stroke
				(width 0.1524)
				(type default)
			)
			(layer "F.SilkS")
		)
		(fp_line
			(start 0.7874 -0.4064)
			(end 0.7874 0.4064)
			(stroke
				(width 0.1524)
				(type default)
			)
			(layer "F.SilkS")
		)
		(fp_line
			(start 0.7874 0.4064)
			(end -0.7874 0.4064)
			(stroke
				(width 0.1524)
				(type default)
			)
			(layer "F.SilkS")
		)
		(fp_line
			(start -0.67945 -0.305054)
			(end -0.12065 -0.305054)
			(stroke
				(width 0.1)
				(type default)
			)
			(layer "F.Fab")
		)
		(fp_line
			(start -0.67945 0.3048)
			(end -0.67945 -0.305054)
			(stroke
				(width 0.1)
				(type default)
			)
			(layer "F.Fab")
		)
		(fp_line
			(start -0.12065 -0.305054)
			(end -0.12065 -0.2794)
			(stroke
				(width 0.1)
				(type default)
			)
			(layer "F.Fab")
		)
		(fp_line
			(start -0.12065 -0.2794)
			(end 0.12065 -0.2794)
			(stroke
				(width 0.1)
				(type default)
			)
			(layer "F.Fab")
		)
		(fp_line
			(start -0.12065 0.2794)
			(end -0.12065 0.3048)
			(stroke
				(width 0.1)
				(type default)
			)
			(layer "F.Fab")
		)
		(fp_line
			(start -0.12065 0.3048)
			(end -0.67945 0.3048)
			(stroke
				(width 0.1)
				(type default)
			)
			(layer "F.Fab")
		)
		(fp_line
			(start 0.120396 0.2794)
			(end -0.12065 0.2794)
			(stroke
				(width 0.1)
				(type default)
			)
			(layer "F.Fab")
		)
		(fp_line
			(start 0.120396 0.3048)
			(end 0.120396 0.2794)
			(stroke
				(width 0.1)
				(type default)
			)
			(layer "F.Fab")
		)
		(fp_line
			(start 0.12065 -0.3048)
			(end 0.67945 -0.3048)
			(stroke
				(width 0.1)
				(type default)
			)
			(layer "F.Fab")
		)
		(fp_line
			(start 0.12065 -0.2794)
			(end 0.12065 -0.3048)
			(stroke
				(width 0.1)
				(type default)
			)
			(layer "F.Fab")
		)
		(fp_line
			(start 0.67945 -0.3048)
			(end 0.67945 0.3048)
			(stroke
				(width 0.1)
				(type default)
			)
			(layer "F.Fab")
		)
		(fp_line
			(start 0.67945 0.3048)
			(end 0.120396 0.3048)
			(stroke
				(width 0.1)
				(type default)
			)
			(layer "F.Fab")
		)
		(pad "1" smd circle
			(at -0.40005 0)
			(size 0 0)
			(layers "F.Cu" "F.Mask" "F.Paste")
			(net "PVNN_MAIN_CPU0_FB_RC")
		)
		(pad "2" smd circle
			(at 0.40005 0)
			(size 0 0)
			(layers "F.Cu" "F.Mask" "F.Paste")
			(net "PVNN_MAIN_CPU0")
		)
	)
)
